FILE_TYPE = CONNECTIVITY;
{Allegro Design Entry HDL 17.4-2019 S026 (4007227) 1/17/2022}
"PAGE_NUMBER" = 232;
0"NC";
1"GND\g";
2"GND\g";
3"P3V3_AUX\g";
4"GND\g";
5"GND\g";
6"GND\g";
7"GND\g";
8"P3V3_AUX\g";
9"VFG_3P3A_CLK_GEN\g";
10"GND\g";
11"P3V3_AUX\g";
12"GND\g";
13"GND\g";
14"P3V3_AUX\g";
15"P3V3_AUX\g";
16"CLK_GEN2_GPU_FPGA_OE_N";
17"GPU_FPGA_READY_N";
18"GND\g";
19"CLK_GEN2_XTAL_IN";
20"CLK_GEN2_XTAL_OUT";
21"GND\g";
22"GND\g";
23"P3V3_AUX\g";
24"P3V3_AUX\g";
25"VFG3P3_CLK_GEN\g";
26"VFG_3P3A_CLK_GEN\g";
27"VFG3P3_CLK_GEN\g";
28"CLK_GEN2_SMB_SADR"CDS_PHYS_NET_NAME"CLK_GEN2_SMB_SADR";
29"SMB_HOST_CLK_GEN2_3V3AUX_SCL";
30"SMB_HOST_CLK_GEN2_3V3AUX_SDA";
31"CLK_GEN2_BMC_RC_OE_R3_N";
32"CLK_100M_BMC_RC_DP_R";
33"CLK_100M_BMC_RC_DN_R";
34"CLK_100M_GPU_FPGA_DP_R";
35"CLK_100M_GPU_FPGA_DN_R";
36"CLK_GEN2_GPU_OE_N";
37"P3V3_PWRGD_CLKGEN"CDS_PHYS_NET_NAME"P3V3_PWRGD_CLKGEN";
38"FG_SS_EN"CDS_PHYS_NET_NAME"FG_SS_EN";
39"CLK_100M_BMC_RC_DN";
40"CLK_100M_BMC_RC_DP";
41"CLK_GEN2_GPU_FPGA_OE_OR_N";
42"CLK_GEN2_XTAL_IN_R";
43"CLK_GEN2_BMC_RC_OE_N";
44"FG_SS_EN"CDS_PHYS_NET_NAME"FG_SS_EN";
45"CLK_GEN2_SMB_SADR"CDS_PHYS_NET_NAME"CLK_GEN2_SMB_SADR";
46"GPU_FPGA_READY_R_N";
47"P3V3_PWRGD_CLKGEN"CDS_PHYS_NET_NAME"P3V3_PWRGD_CLKGEN";
48"CLK_100M_GPU_FPGA_DP";
49"CLK_100M_GPU_FPGA_DN";
50"CLK_GEN2_GPU_FPGA_OE_OR_N";
51"CLK_GEN2_GPU_FPGA_OE_R2_N";
%"UNIVERSAL_GND"
"1","(-7250,3700)","0","pure_quanta_power","I11";
;
CDS_LIB"pure_quanta_power"
HDL_POWER"GND";
"A"1;
%"UNIVERSAL_GND"
"1","(-7125,3800)","0","pure_quanta_power","I12";
;
CDS_LIB"pure_quanta_power"
HDL_POWER"GND";
"A"2;
%"Q_XTAL_4P_13BI_24GND"
"1","(-6800,4025)","0","pure_quanta","I14";
;
LOCATION"Y8003"
$SEC"1"
CDS_SEC"1"
VALUE"25MHZ"
PART_TYPE"SMLF"
MATERIAL"MISC"
CDS_LIB"pure_quanta"
CDS_LMAN_SYM_OUTLINE"-125,175,125,-175"
PIN_NAMES_ROTATE"True"
PART_NUMBER"BG6250000L4";
"X2"
$PN"3"20;
"G2"
$PN"4"5;
"G1"
$PN"2"2;
"X1"
$PN"1"42;
%"UNIVERSAL_POWER"
"1","(-6325,2075)","0","pure_quanta_power","I15";
;
HDL_POWER"P3V3_AUX"
CDS_LIB"pure_quanta_power";
"A"3;
%"Q_RES"
"1","(-6200,3500)","0","pure_quanta","I16";
;
LOCATION"R4076"
$SEC"1"
CDS_SEC"1"
PACK_TYPE"0402LF"
WATTAGE"1/16W"
TOLERANCE"5%"
VALUE"0"
MATERIAL"CHIP"
CDS_LIB"pure_quanta"
PART_NUMBER"CS00002JB13";
"B"
$PN"2"36;
"A"
$PN"1"41;
%"UNIVERSAL_GND"
"1","(-6375,3675)","0","pure_quanta_power","I19";
;
CDS_LIB"pure_quanta_power"
HDL_POWER"GND";
"A"4;
%"UNIVERSAL_GND"
"1","(-6475,3800)","0","pure_quanta_power","I20";
;
CDS_LIB"pure_quanta_power"
HDL_POWER"GND";
"A"5;
%"Q_RES"
"1","(-6200,3550)","0","pure_quanta","I22";
;
LOCATION"R4075"
$SEC"1"
CDS_SEC"1"
VALUE"0"
MATERIAL"CHIP"
WATTAGE"1/16W"
TOLERANCE"5%"
PACK_TYPE"0402LF"
CDS_LIB"pure_quanta"
PART_NUMBER"CS00002JB13";
"B"
$PN"2"31;
"A"
$PN"1"43;
%"UNIVERSAL_GND"
"1","(-5450,1175)","0","pure_quanta_power","I25";
;
CDS_LIB"pure_quanta_power"
HDL_POWER"GND";
"A"6;
%"74LVC1G32GW"
"1","(-5125,1450)","0","pure_quanta","I26";
;
LOCATION"U248"
$SEC"1"
CDS_SEC"1"
PACK_TYPE"SMLF"
MATERIAL"IC"
VALUE"74LVC1G32GW"
CDS_LIB"pure_quanta"
NEEDS_NO_SIZE"TRUE"
PART_NUMBER"ALVC1G32007";
"GND"
$PN"3"6;
"O"
$PN"4"50;
"I1"
$PN"2"51;
"VCC"
$PN"5"23;
"I0"
$PN"1"46;
%"UNIVERSAL_GND"
"1","(-5275,1875)","0","pure_quanta_power","I27";
;
CDS_LIB"pure_quanta_power"
HDL_POWER"GND";
"A"7;
%"Q_CAP"
"1","(-5275,2125)","0","pure_quanta","I28";
;
LOCATION"C1882"
$SEC"1"
CDS_SEC"1"
VOLTAGE"25V"
VALUE"0.1UF"
MATERIAL"X7R"
TOLERANCE"10%"
PACK_TYPE"0402"
CDS_LIB"pure_quanta"
PART_NUMBER"CH4104K1B00";
"B"
$PN"2"7;
"A"
$PN"1"23;
%"UNIVERSAL_POWER"
"1","(-5275,2550)","0","pure_quanta_power","I29";
;
HDL_POWER"P3V3_AUX"
CDS_LIB"pure_quanta_power";
"A"23;
%"UNIVERSAL_POWER"
"1","(-7975,4200)","0","pure_quanta_power","I30";
;
HDL_POWER"P3V3_AUX"
CDS_LIB"pure_quanta_power";
"A"8;
%"Q_RES"
"1","(-6375,4575)","0","pure_quanta","I31";
;
LOCATION"R4501"
$SEC"1"
CDS_SEC"1"
PACK_TYPE"0402LF"
MATERIAL"CHIP"
WATTAGE"1/16W"
VALUE"0"
TOLERANCE"5%"
CDS_LIB"pure_quanta"
PART_NUMBER"CS00002JB13";
"B"
$PN"2"19;
"A"
$PN"1"42;
%"UNIVERSAL_POWER"
"1","(-6400,5525)","0","pure_quanta_power","I32";
;
HDL_POWER"P3V3_AUX"
CDS_LIB"pure_quanta_power";
"A"24;
%"Q_INDUCTOR"
"1","(-6050,5425)","0","pure_quanta","I33";
;
LOCATION"L17"
$SEC"1"
CDS_SEC"1"
MATERIAL"IND"
PACK_TYPE"SMLF"
VALUE"FCM2012KF-601T/0.5A"
NEEDS_NO_SIZE"TRUE"
CDS_LIB"pure_quanta"
PART_NUMBER"CX601T05003";
"1"
$PN"1"24;
"2"
$PN"2"25;
%"UNIVERSAL_POWER"
"1","(-5750,4500)","0","pure_quanta_power","I34";
;
HDL_POWER"VFG3P3_CLK_GEN"
CDS_LIB"pure_quanta_power";
"A"27;
%"UNIVERSAL_POWER"
"1","(-5400,4575)","0","pure_quanta_power","I35";
;
HDL_POWER"VFG_3P3A_CLK_GEN"
CDS_LIB"pure_quanta_power";
"A"9;
%"Q_CAP"
"1","(-5700,5200)","0","pure_quanta","I36";
;
LOCATION"C1883"
$SEC"1"
CDS_SEC"1"
VALUE"10UF"
MATERIAL"X6S"
TOLERANCE"10%"
VOLTAGE"25V"
PACK_TYPE"C0805"
CDS_LIB"pure_quanta"
PART_NUMBER"CH6104KEA00";
"B"
$PN"2"22;
"A"
$PN"1"25;
%"Q_CAP"
"1","(-5300,5200)","0","pure_quanta","I37";
;
LOCATION"C2257"
$SEC"1"
CDS_SEC"1"
PACK_TYPE"0402"
TOLERANCE"10%"
MATERIAL"X7R"
VALUE"0.1UF"
VOLTAGE"25V"
CDS_LIB"pure_quanta"
PART_NUMBER"CH4104K1B00";
"B"
$PN"2"22;
"A"
$PN"1"25;
%"UNIVERSAL_POWER"
"1","(-5300,5550)","0","pure_quanta_power","I38";
;
HDL_POWER"VFG3P3_CLK_GEN"
CDS_LIB"pure_quanta_power";
"A"25;
%"UNIVERSAL_GND"
"1","(-4500,4850)","0","pure_quanta_power","I39";
;
CDS_LIB"pure_quanta_power"
HDL_POWER"GND";
"A"22;
%"Q_CAP"
"1","(-4975,5200)","0","pure_quanta","I40";
;
LOCATION"C1886"
$SEC"1"
CDS_SEC"1"
VALUE"0.1UF"
VOLTAGE"25V"
TOLERANCE"10%"
MATERIAL"X7R"
PACK_TYPE"0402"
CDS_LIB"pure_quanta"
PART_NUMBER"CH4104K1B00";
"B"
$PN"2"22;
"A"
$PN"1"25;
%"Q_CAP"
"1","(-4750,5200)","0","pure_quanta","I41";
;
LOCATION"C1889"
$SEC"1"
CDS_SEC"1"
VOLTAGE"25V"
VALUE"0.1UF"
TOLERANCE"10%"
MATERIAL"X7R"
PACK_TYPE"0402"
CDS_LIB"pure_quanta"
PART_NUMBER"CH4104K1B00";
"B"
$PN"2"22;
"A"
$PN"1"25;
%"Q_CAP"
"1","(-4500,5200)","0","pure_quanta","I42";
;
LOCATION"C95"
$SEC"1"
CDS_SEC"1"
VOLTAGE"25V"
TOLERANCE"10%"
MATERIAL"X7R"
VALUE"0.1UF"
PACK_TYPE"0402"
CDS_LIB"pure_quanta"
PART_NUMBER"CH4104K1B00";
"B"
$PN"2"22;
"A"
$PN"1"25;
%"Q_RES"
"1","(-4175,5400)","0","pure_quanta","I43";
;
LOCATION"R4077"
$SEC"1"
CDS_SEC"1"
PACK_TYPE"0402LF"
WATTAGE"1/16W"
MATERIAL"CHIP"
TOLERANCE"1%"
VALUE"1"
CDS_LIB"pure_quanta"
PART_NUMBER"CS-1002FB04";
"B"
$PN"2"26;
"A"
$PN"1"25;
%"UNIVERSAL_GND"
"1","(-2650,925)","0","pure_quanta_power","I45";
;
CDS_LIB"pure_quanta_power"
HDL_POWER"GND";
"A"10;
%"Q_RES"
"2","(-2650,1200)","2","pure_quanta","I46";
;
LOCATION"R4079"
$SEC"1"
CDS_SEC"1"
VALUE"10K"
TOLERANCE"1%"
PACK_TYPE"0402LF"
WATTAGE"1/16W"
MATERIAL"CHIP"
CDS_LIB"pure_quanta"
PART_NUMBER"CS31002FB08";
"A"
$PN"1"44;
"B"
$PN"2"10;
%"Q_RES"
"2","(-2650,1675)","2","pure_quanta","I47";
;
LOCATION"R4078"
$SEC"1"
CDS_SEC"1"
MATERIAL"EMPTY"
TOLERANCE"1%"
VALUE"10K"
WATTAGE"1/16W"
PACK_TYPE"0402LF"
CDS_LIB"pure_quanta"
PART_NUMBER"CS31002FB08";
"A"
$PN"1"11;
"B"
$PN"2"44;
%"UNIVERSAL_POWER"
"1","(-2650,1950)","0","pure_quanta_power","I48";
;
HDL_POWER"P3V3_AUX"
CDS_LIB"pure_quanta_power";
"A"11;
%"UNIVERSAL_GND"
"1","(-6300,725)","0","pure_quanta_power","I5";
;
CDS_LIB"pure_quanta_power"
HDL_POWER"GND";
"A"12;
%"Q_RES"
"1","(-2725,3750)","0","pure_quanta","I50";
;
LOCATION"R3338"
$SEC"1"
CDS_SEC"1"
WATTAGE"1/16W"
PACK_TYPE"0402LF"
VALUE"0"
MATERIAL"CHIP"
TOLERANCE"5%"
CDS_LIB"pure_quanta"
PART_NUMBER"CS00002JB13";
"B"
$PN"2"49;
"A"
$PN"1"35;
%"Q_RES"
"1","(-2725,3800)","0","pure_quanta","I51";
;
LOCATION"R3337"
$SEC"1"
CDS_SEC"1"
MATERIAL"CHIP"
VALUE"0"
CDS_LIB"pure_quanta"
WATTAGE"1/16W"
TOLERANCE"5%"
PACK_TYPE"0402LF"
PART_NUMBER"CS00002JB13";
"B"
$PN"2"48;
"A"
$PN"1"34;
%"Q_RES"
"1","(-2725,3900)","0","pure_quanta","I52";
;
LOCATION"R3336"
$SEC"1"
CDS_SEC"1"
MATERIAL"CHIP"
VALUE"0"
CDS_LIB"pure_quanta"
PACK_TYPE"0402LF"
TOLERANCE"5%"
WATTAGE"1/16W"
PART_NUMBER"CS00002JB13";
"B"
$PN"2"39;
"A"
$PN"1"33;
%"Q_RES"
"1","(-2725,3950)","0","pure_quanta","I53";
;
LOCATION"R3335"
$SEC"1"
CDS_SEC"1"
VALUE"0"
MATERIAL"CHIP"
PACK_TYPE"0402LF"
TOLERANCE"5%"
WATTAGE"1/16W"
CDS_LIB"pure_quanta"
PART_NUMBER"CS00002JB13";
"B"
$PN"2"40;
"A"
$PN"1"32;
%"UNIVERSAL_GND"
"1","(-1325,950)","0","pure_quanta_power","I54";
;
CDS_LIB"pure_quanta_power"
HDL_POWER"GND";
"A"13;
%"Q_RES"
"2","(-1325,1225)","2","pure_quanta","I55";
;
LOCATION"R4082"
$SEC"1"
CDS_SEC"1"
VALUE"10K"
MATERIAL"EMPTY"
WATTAGE"1/16W"
TOLERANCE"1%"
PACK_TYPE"0402LF"
CDS_LIB"pure_quanta"
PART_NUMBER"CS31002FB08";
"A"
$PN"1"45;
"B"
$PN"2"13;
%"Q_RES"
"2","(-1325,1700)","2","pure_quanta","I56";
;
LOCATION"R4081"
$SEC"1"
CDS_SEC"1"
WATTAGE"1/16W"
TOLERANCE"1%"
VALUE"10K"
PACK_TYPE"0402LF"
MATERIAL"CHIP"
CDS_LIB"pure_quanta"
PART_NUMBER"CS31002FB08";
"A"
$PN"1"14;
"B"
$PN"2"45;
%"UNIVERSAL_POWER"
"1","(-1325,1975)","0","pure_quanta_power","I57";
;
HDL_POWER"P3V3_AUX"
CDS_LIB"pure_quanta_power";
"A"14;
%"Q_RES"
"2","(-1325,2500)","2","pure_quanta","I59";
;
LOCATION"R4080"
$SEC"1"
CDS_SEC"1"
VALUE"10K"
TOLERANCE"1%"
WATTAGE"1/16W"
MATERIAL"CHIP"
PACK_TYPE"0402LF"
CDS_LIB"pure_quanta"
PART_NUMBER"CS31002FB08";
"A"
$PN"1"15;
"B"
$PN"2"47;
%"Q_RES"
"1","(-6625,1400)","0","pure_quanta","I6";
;
LOCATION"R3327"
$SEC"1"
CDS_SEC"1"
VALUE"0"
MATERIAL"CHIP"
TOLERANCE"5%"
PACK_TYPE"0402LF"
WATTAGE"1/16W"
CDS_LIB"pure_quanta"
PART_NUMBER"CS00002JB13";
"B"
$PN"2"51;
"A"
$PN"1"16;
%"UNIVERSAL_POWER"
"1","(-1325,2775)","0","pure_quanta_power","I60";
;
HDL_POWER"P3V3_AUX"
CDS_LIB"pure_quanta_power";
"A"15;
%"UNIVERSAL_GND"
"1","(-3625,4850)","0","pure_quanta_power","I66";
;
CDS_LIB"pure_quanta_power"
HDL_POWER"GND";
"A"21;
%"Q_CAP"
"1","(-3950,5175)","0","pure_quanta","I68";
;
LOCATION"C1884"
$SEC"1"
CDS_SEC"1"
VALUE"1UF"
PACK_TYPE"C0402"
VOLTAGE"25V"
TOLERANCE"10%"
MATERIAL"X6S"
CDS_LIB"pure_quanta"
BOM_COST"VR_SYSTEM "
PART_NUMBER"CH5104KEB02";
"B"
$PN"2"21;
"A"
$PN"1"26;
%"Q_CAP"
"1","(-3625,5175)","0","pure_quanta","I69";
;
LOCATION"C97"
$SEC"1"
CDS_SEC"1"
PACK_TYPE"0402"
VALUE"0.1UF"
MATERIAL"X7R"
VOLTAGE"25V"
TOLERANCE"10%"
CDS_LIB"pure_quanta"
PART_NUMBER"CH4104K1B00";
"B"
$PN"2"21;
"A"
$PN"1"26;
%"Q_RES"
"1","(-6625,1500)","0","pure_quanta","I7";
;
LOCATION"R3326"
$SEC"1"
CDS_SEC"1"
MATERIAL"CHIP"
VALUE"0"
WATTAGE"1/16W"
TOLERANCE"5%"
PACK_TYPE"0402LF"
CDS_LIB"pure_quanta"
PART_NUMBER"CS00002JB13";
"B"
$PN"2"46;
"A"
$PN"1"17;
%"UNIVERSAL_POWER"
"1","(-3625,5500)","0","pure_quanta_power","I70";
;
HDL_POWER"VFG_3P3A_CLK_GEN"
CDS_LIB"pure_quanta_power";
"A"26;
%"UNIVERSAL_GND"
"1","(-3600,2700)","0","pure_quanta_power","I71";
;
CDS_LIB"pure_quanta_power"
HDL_POWER"GND";
"A"18;
%"Q_RES"
"2","(-7975,3925)","0","pure_quanta","I73";
;
LOCATION"R4521"
$SEC"1"
CDS_SEC"1"
PACK_TYPE"0402LF"
TOLERANCE"1%"
WATTAGE"1/16W"
MATERIAL"CHIP"
VALUE"1K"
CDS_LIB"pure_quanta"
PART_NUMBER"CS21002FB06";
"A"
$PN"1"8;
"B"
$PN"2"43;
%"Q_RES"
"2","(-6325,1800)","0","pure_quanta","I74";
;
LOCATION"R3322"
$SEC"1"
CDS_SEC"1"
TOLERANCE"1%"
PACK_TYPE"0402LF"
WATTAGE"1/16W"
MATERIAL"CHIP"
VALUE"1K"
CDS_LIB"pure_quanta"
PART_NUMBER"CS21002FB06";
"A"
$PN"1"3;
"B"
$PN"2"51;
%"Q_CAP"
"1","(-7250,3900)","2","pure_quanta","I75";
;
LOCATION"C71"
$SEC"1"
CDS_SEC"1"
VALUE"4.7PF"
VOLTAGE"50V"
PACK_TYPE"C0402"
MATERIAL"NPO"
TOLERANCE"0.1P"
CDS_LIB"pure_quanta"
PART_NUMBER"CH-4716TB06";
"B"
$PN"2"1;
"A"
$PN"1"42;
%"Q_CAP"
"1","(-6375,3900)","0","pure_quanta","I76";
;
LOCATION"C94"
$SEC"1"
CDS_SEC"1"
PACK_TYPE"C0402"
VALUE"4.7PF"
MATERIAL"NPO"
TOLERANCE"0.1P"
VOLTAGE"50V"
CDS_LIB"pure_quanta"
PART_NUMBER"CH-4716TB06";
"B"
$PN"2"4;
"A"
$PN"1"20;
%"9FGL0251DKILFT"
"1","(-4300,3700)","0","pure_quanta","I77";
;
LOCATION"U247"
SEC"1"
PART_TYPE"SMLF"
MATERIAL"IC"
VALUE"9FGL0251DKILFT"
CDS_LMAN_SYM_OUTLINE"-400,700,400,-700"
NEEDS_NO_SIZE"TRUE"
CDS_LIB"pure_quanta"
SEC_TYPE""
PART_NUMBER"AL000251002";
"TH_GND"
$PN"25"18;
"GNDXTAL"
$PN"24"18;
"^VSS_EN_TRI"
$PN"23"38;
"^CKPWRGD_PD# \B"
$PN"22"37;
"GND_21"
$PN"21"18;
"VDD3.3_20"
$PN"20"27;
"VOE1# \B"
$PN"19"36;
"DIF1# \B"
$PN"18"35;
"DIF1"
$PN"17"34;
"VDDA3.3"
$PN"16"9;
"GNDA"
$PN"15"18;
"DIF0# \B"
$PN"14"33;
"DIF0"
$PN"13"32;
"VOE0# \B"
$PN"12"31;
"VDD3.3_11"
$PN"11"27;
"GND_10"
$PN"10"18;
"SDATA_3.3"
$PN"9"30;
"SCLK_3.3"
$PN"8"29;
"VDDDIG3.3"
$PN"7"27;
"GNDDIG"
$PN"6"18;
"GNDREF"
$PN"5"18;
"VSADR||REF3.3"
$PN"4"28;
"VDDXTAL3.3"
$PN"3"27;
"X2"
$PN"2"20;
"XIN||CLKIN_25"
$PN"1"19;
%"Q_RES"
"2","(-6300,1175)","0","pure_quanta","I8";
;
LOCATION"R4514"
$SEC"1"
CDS_SEC"1"
TOLERANCE"1%"
VALUE"4.7K"
WATTAGE"1/16W"
MATERIAL"EMPTY"
PACK_TYPE"0402LF"
CDS_LIB"pure_quanta"
PART_NUMBER"CS24702FB06";
"A"
$PN"1"51;
"B"
$PN"2"12;
END.
